# T6G (Grand Teton) — schematic netlist excerpt (pin names and nets, part order shuffled) for the footprints in the layout excerpt that follows; sources: Cadence DE-HDL packaged netlist, KiCad conversion of 04192023_DAF0TMB3IC0_F0TG_MB_C_brd_V02_OCP.brd

PC2141  Q_CAP  22UF 16V 20% X6S  pkg C0805  page 140 : A = P12V_OCP_V3_2 ; B = GND
C267  Q_CAP  22UF 4V 20% X6S  pkg C0402  page 69 : A = PVDDCR_CPU0_P0 ; B = GND

(kicad_pcb
	(version 20260206)
	(generator "pcbnew")
	(generator_version "10.0")
	(general
		(thickness 1.6)
		(legacy_teardrops no)
	)
	(paper "A4")
	(title_block
		(title "04192023_DAF0TMB3IC0_F0TG_MB_C_brd_V02_OCP.brd")
		(comment 1 "Grand Teton / footprints 5442-5443 of 8354")
	)
	(layers
		(0 "F.Cu" signal "TOP")
		(4 "In1.Cu" signal "GND")
		(6 "In2.Cu" signal "IN1")
		(8 "In3.Cu" signal "GND1")
		(10 "In4.Cu" signal "IN2")
		(12 "In5.Cu" signal "GND2")
		(14 "In6.Cu" signal "IN3")
		(16 "In7.Cu" signal "GND3")
		(18 "In8.Cu" signal "VCC")
		(20 "In9.Cu" signal "VCC1")
		(22 "In10.Cu" signal "GND4")
		(24 "In11.Cu" signal "IN4")
		(26 "In12.Cu" signal "GND5")
		(28 "In13.Cu" signal "IN5")
		(30 "In14.Cu" signal "GND6")
		(32 "In15.Cu" signal "IN6")
		(34 "In16.Cu" signal "GND7")
		(2 "B.Cu" signal "BOTTOM")
		(9 "F.Adhes" user "F.Adhesive")
		(11 "B.Adhes" user "B.Adhesive")
		(13 "F.Paste" user "Package Geometry/Pastemask Top")
		(15 "B.Paste" user "Package Geometry/Pastemask Bottom")
		(5 "F.SilkS" user "Ref Des/Silkscreen Top")
		(7 "B.SilkS" user "Ref Des/Silkscreen Bottom")
		(1 "F.Mask" user "Board Geometry/Soldermask Top")
		(3 "B.Mask" user "Board Geometry/Soldermask Bottom")
		(17 "Dwgs.User" user "User.Drawings")
		(19 "Cmts.User" user "User.Comments")
		(21 "Eco1.User" user "User.Eco1")
		(23 "Eco2.User" user "User.Eco2")
		(25 "Edge.Cuts" user "Board Geometry/Outline")
		(27 "Margin" user)
		(31 "F.CrtYd" user "Package Geometry/Place Bound Top")
		(29 "B.CrtYd" user "Package Geometry/Place Bound Bottom")
		(35 "F.Fab" user "Ref Des/Assembly Top")
		(33 "B.Fab" user "Ref Des/Assembly Bottom")
	)
	(footprint ""
		(layer "B.Cu")
		(at 364.407958 -245.487952)
		(property "Reference" "C267"
			(at 0 0 0)
			(layer "B.SilkS")
			(hide yes)
			(effects
				(font
					(size 1.27 1.27)
				)
				(justify mirror)
			)
		)
		(property "Value" ""
			(at 0 0 0)
			(layer "B.Fab")
			(effects
				(font
					(size 1.27 1.27)
				)
				(justify mirror)
			)
		)
		(duplicate_pad_numbers_are_jumpers no)
		(fp_line
			(start -0.7874 -0.4064)
			(end -0.7874 0.4064)
			(stroke
				(width 0.1524)
				(type default)
			)
			(layer "B.SilkS")
		)
		(fp_line
			(start -0.7874 0.4064)
			(end 0.7874 0.4064)
			(stroke
				(width 0.1524)
				(type default)
			)
			(layer "B.SilkS")
		)
		(fp_line
			(start 0.7874 -0.4064)
			(end -0.7874 -0.4064)
			(stroke
				(width 0.1524)
				(type default)
			)
			(layer "B.SilkS")
		)
		(fp_line
			(start 0.7874 0.4064)
			(end 0.7874 -0.4064)
			(stroke
				(width 0.1524)
				(type default)
			)
			(layer "B.SilkS")
		)
		(fp_line
			(start -0.67945 -0.3048)
			(end -0.67945 0.3048)
			(stroke
				(width 0.1)
				(type default)
			)
			(layer "B.Fab")
		)
		(fp_line
			(start -0.67945 0.3048)
			(end -0.120396 0.3048)
			(stroke
				(width 0.1)
				(type default)
			)
			(layer "B.Fab")
		)
		(fp_line
			(start -0.12065 -0.3048)
			(end -0.67945 -0.3048)
			(stroke
				(width 0.1)
				(type default)
			)
			(layer "B.Fab")
		)
		(fp_line
			(start -0.12065 -0.2794)
			(end -0.12065 -0.3048)
			(stroke
				(width 0.1)
				(type default)
			)
			(layer "B.Fab")
		)
		(fp_line
			(start -0.120396 0.2794)
			(end 0.12065 0.2794)
			(stroke
				(width 0.1)
				(type default)
			)
			(layer "B.Fab")
		)
		(fp_line
			(start -0.120396 0.3048)
			(end -0.120396 0.2794)
			(stroke
				(width 0.1)
				(type default)
			)
			(layer "B.Fab")
		)
		(fp_line
			(start 0.12065 -0.305054)
			(end 0.12065 -0.2794)
			(stroke
				(width 0.1)
				(type default)
			)
			(layer "B.Fab")
		)
		(fp_line
			(start 0.12065 -0.2794)
			(end -0.12065 -0.2794)
			(stroke
				(width 0.1)
				(type default)
			)
			(layer "B.Fab")
		)
		(fp_line
			(start 0.12065 0.2794)
			(end 0.12065 0.3048)
			(stroke
				(width 0.1)
				(type default)
			)
			(layer "B.Fab")
		)
		(fp_line
			(start 0.12065 0.3048)
			(end 0.67945 0.3048)
			(stroke
				(width 0.1)
				(type default)
			)
			(layer "B.Fab")
		)
		(fp_line
			(start 0.67945 -0.305054)
			(end 0.12065 -0.305054)
			(stroke
				(width 0.1)
				(type default)
			)
			(layer "B.Fab")
		)
		(fp_line
			(start 0.67945 0.3048)
			(end 0.67945 -0.305054)
			(stroke
				(width 0.1)
				(type default)
			)
			(layer "B.Fab")
		)
		(pad "1" smd circle
			(at 0.40005 0 180)
			(size 0 0)
			(layers "B.Cu" "B.Mask" "B.Paste")
			(net "PVDDCR_CPU0_P0")
		)
		(pad "2" smd circle
			(at -0.40005 0 180)
			(size 0 0)
			(layers "B.Cu" "B.Mask" "B.Paste")
			(net "GND")
		)
	)
	(footprint ""
		(layer "B.Cu")
		(at 64.889126 -20.04822)
		(property "Reference" "PC2141"
			(at 0 0 0)
			(layer "B.SilkS")
			(hide yes)
			(effects
				(font
					(size 1.27 1.27)
				)
				(justify mirror)
			)
		)
		(property "Value" ""
			(at 0 0 0)
			(layer "B.Fab")
			(effects
				(font
					(size 1.27 1.27)
				)
				(justify mirror)
			)
		)
		(duplicate_pad_numbers_are_jumpers no)
		(fp_line
			(start -1.524 -0.762)
			(end -1.524 0.762)
			(stroke
				(width 0.1524)
				(type default)
			)
			(layer "B.SilkS")
		)
		(fp_line
			(start -1.524 0.762)
			(end 1.524 0.762)
			(stroke
				(width 0.1524)
				(type default)
			)
			(layer "B.SilkS")
		)
		(fp_line
			(start 1.524 -0.762)
			(end -1.524 -0.762)
			(stroke
				(width 0.1524)
				(type default)
			)
			(layer "B.SilkS")
		)
		(fp_line
			(start 1.524 0.762)
			(end 1.524 -0.762)
			(stroke
				(width 0.1524)
				(type default)
			)
			(layer "B.SilkS")
		)
		(fp_line
			(start -1.1049 -0.724916)
			(end 1.1049 -0.724916)
			(stroke
				(width 0.1)
				(type default)
			)
			(layer "B.Fab")
		)
		(fp_line
			(start -1.1049 0.724916)
			(end -1.1049 -0.724916)
			(stroke
				(width 0.1)
				(type default)
			)
			(layer "B.Fab")
		)
		(fp_line
			(start 1.1049 -0.724916)
			(end 1.1049 0.724916)
			(stroke
				(width 0.1)
				(type default)
			)
			(layer "B.Fab")
		)
		(fp_line
			(start 1.1049 0.724916)
			(end -1.1049 0.724916)
			(stroke
				(width 0.1)
				(type default)
			)
			(layer "B.Fab")
		)
		(pad "1" smd rect
			(at 0.889 0)
			(size 1.016 1.27)
			(layers "B.Cu" "B.Mask" "B.Paste")
			(net "P12V_OCP_V3_2")
		)
		(pad "2" smd rect
			(at -0.889 0)
			(size 1.016 1.27)
			(layers "B.Cu" "B.Mask" "B.Paste")
			(net "GND")
		)
	)
)
